(kicad_pcb
	(version 20260206)
	(generator "pcbnew")
	(generator_version "10.0")
	(general
		(thickness 1.6)
		(legacy_teardrops no)
	)
	(paper "A4")
	(title_block
		(title "baseboard — 13948-1b.1110WZS1818.brd")
		(comment 1 "Honey Badger (Wiwynn) / footprints 2173-2180 of 2523")
	)
	(layers
		(0 "F.Cu" signal "TOP")
		(4 "In1.Cu" signal "L2GND")
		(6 "In2.Cu" signal "L3")
		(8 "In3.Cu" signal "L4VCC")
		(10 "In4.Cu" signal "L5VCC")
		(12 "In5.Cu" signal "L6")
		(14 "In6.Cu" signal "L7GND")
		(2 "B.Cu" signal "BOTTOM")
		(9 "F.Adhes" user "F.Adhesive")
		(11 "B.Adhes" user "B.Adhesive")
		(13 "F.Paste" user "Package Geometry/Pastemask Top")
		(15 "B.Paste" user "Package Geometry/Pastemask Bottom")
		(5 "F.SilkS" user "Ref Des/Silkscreen Top")
		(7 "B.SilkS" user "Ref Des/Silkscreen Bottom")
		(1 "F.Mask" user "Board Geometry/Soldermask Top")
		(3 "B.Mask" user "Board Geometry/Soldermask Bottom")
		(17 "Dwgs.User" user "User.Drawings")
		(19 "Cmts.User" user "User.Comments")
		(21 "Eco1.User" user "User.Eco1")
		(23 "Eco2.User" user "User.Eco2")
		(25 "Edge.Cuts" user "Board Geometry/Outline")
		(27 "Margin" user)
		(31 "F.CrtYd" user "Package Geometry/Place Bound Top")
		(29 "B.CrtYd" user "Package Geometry/Place Bound Bottom")
		(35 "F.Fab" user "Ref Des/Assembly Top")
		(33 "B.Fab" user "Ref Des/Assembly Bottom")
	)
	(footprint ""
		(layer "B.Cu")
		(at 117.329966 -46.228 180)
		(property "Reference" "SC979"
			(at 0 0 0)
			(layer "B.SilkS")
			(hide yes)
			(effects
				(font
					(size 1.27 1.27)
				)
				(justify mirror)
			)
		)
		(property "Value" "SCD1U16V2KX-3GP"
			(at -1.1811 -2.7051 180)
			(unlocked yes)
			(layer "B.Fab")
			(hide yes)
			(effects
				(font
					(size 1.016 1.016)
					(thickness 0.1524)
				)
				(justify mirror)
			)
		)
		(property "Device Type" "C402H22"
			(at -1.1811 -4.2291 180)
			(unlocked yes)
			(layer "B.Fab")
			(hide yes)
			(effects
				(font
					(size 1.016 1.016)
					(thickness 0.1524)
				)
				(justify mirror)
			)
		)
		(duplicate_pad_numbers_are_jumpers no)
		(fp_rect
			(start 0.4318 0.9525)
			(end -0.4318 -0.9525)
			(stroke
				(width 0)
				(type default)
			)
			(fill no)
			(layer "B.CrtYd")
		)
		(fp_rect
			(start 0.4318 0.9525)
			(end -0.4318 -0.9525)
			(stroke
				(width 0)
				(type default)
			)
			(fill no)
			(layer "B.Fab")
		)
		(pad "1" smd custom
			(at 0 -0.4445)
			(size 0.1524 0.1524)
			(layers "B.Cu" "B.Mask" "B.Paste")
			(net "P1V8_C")
			(options
				(clearance outline)
				(anchor circle)
			)
			(primitives
				(gr_poly
					(pts
						(arc
							(start 0.3048 0.2032)
							(mid 0.275042 0.275042)
							(end 0.2032 0.3048)
						)
						(arc
							(start -0.2032 0.3048)
							(mid -0.275042 0.275042)
							(end -0.3048 0.2032)
						)
						(arc
							(start -0.3048 -0.2032)
							(mid -0.275042 -0.275042)
							(end -0.2032 -0.3048)
						)
						(arc
							(start 0.2032 -0.3048)
							(mid 0.275042 -0.275042)
							(end 0.3048 -0.2032)
						)
					)
					(width 0)
					(fill yes)
				)
			)
		)
		(pad "2" smd custom
			(at 0 0.4445)
			(size 0.1524 0.1524)
			(layers "B.Cu" "B.Mask" "B.Paste")
			(net "GND")
			(options
				(clearance outline)
				(anchor circle)
			)
			(primitives
				(gr_poly
					(pts
						(arc
							(start 0.3048 0.2032)
							(mid 0.275042 0.275042)
							(end 0.2032 0.3048)
						)
						(arc
							(start -0.2032 0.3048)
							(mid -0.275042 0.275042)
							(end -0.3048 0.2032)
						)
						(arc
							(start -0.3048 -0.2032)
							(mid -0.275042 -0.275042)
							(end -0.2032 -0.3048)
						)
						(arc
							(start 0.2032 -0.3048)
							(mid 0.275042 -0.275042)
							(end 0.3048 -0.2032)
						)
					)
					(width 0)
					(fill yes)
				)
			)
		)
	)
	(footprint ""
		(layer "B.Cu")
		(at 267.081 -16.891 180)
		(property "Reference" "C338"
			(at 0 0 0)
			(layer "B.SilkS")
			(hide yes)
			(effects
				(font
					(size 1.27 1.27)
				)
				(justify mirror)
			)
		)
		(property "Value" "SC1U10V3KX-4GP-U"
			(at 0 -2.8194 180)
			(unlocked yes)
			(layer "B.Fab")
			(hide yes)
			(effects
				(font
					(size 1.016 1.016)
					(thickness 0.1524)
				)
				(justify mirror)
			)
		)
		(property "Device Type" "C603H36"
			(at 0 -4.3434 180)
			(unlocked yes)
			(layer "B.Fab")
			(hide yes)
			(effects
				(font
					(size 1.016 1.016)
					(thickness 0.1524)
				)
				(justify mirror)
			)
		)
		(duplicate_pad_numbers_are_jumpers no)
		(fp_line
			(start -0.508 0)
			(end 0.508 0)
			(stroke
				(width 0.2032)
				(type default)
			)
			(layer "B.SilkS")
		)
		(fp_rect
			(start 0.5842 1.3335)
			(end -0.5842 -1.3335)
			(stroke
				(width 0)
				(type default)
			)
			(fill no)
			(layer "B.CrtYd")
		)
		(fp_rect
			(start 0.5842 1.3335)
			(end -0.5842 -1.3335)
			(stroke
				(width 0)
				(type default)
			)
			(fill no)
			(layer "B.Fab")
		)
		(pad "1" smd custom
			(at 0 -0.762)
			(size 0.2159 0.2159)
			(layers "B.Cu" "B.Mask" "B.Paste")
			(net "P5V_USB")
			(options
				(clearance outline)
				(anchor circle)
			)
			(primitives
				(gr_poly
					(pts
						(arc
							(start -0.3302 0.4318)
							(mid -0.402042 0.402042)
							(end -0.4318 0.3302)
						)
						(arc
							(start -0.4318 -0.3302)
							(mid -0.402042 -0.402042)
							(end -0.3302 -0.4318)
						)
						(arc
							(start 0.3302 -0.4318)
							(mid 0.402042 -0.402042)
							(end 0.4318 -0.3302)
						)
						(arc
							(start 0.4318 0.3302)
							(mid 0.402042 0.402042)
							(end 0.3302 0.4318)
						)
					)
					(width 0)
					(fill yes)
				)
			)
		)
		(pad "2" smd custom
			(at 0 0.762)
			(size 0.2159 0.2159)
			(layers "B.Cu" "B.Mask" "B.Paste")
			(net "GND")
			(options
				(clearance outline)
				(anchor circle)
			)
			(primitives
				(gr_poly
					(pts
						(arc
							(start -0.3302 0.4318)
							(mid -0.402042 0.402042)
							(end -0.4318 0.3302)
						)
						(arc
							(start -0.4318 -0.3302)
							(mid -0.402042 -0.402042)
							(end -0.3302 -0.4318)
						)
						(arc
							(start 0.3302 -0.4318)
							(mid 0.402042 -0.402042)
							(end 0.4318 -0.3302)
						)
						(arc
							(start 0.4318 0.3302)
							(mid 0.402042 0.402042)
							(end 0.3302 0.4318)
						)
					)
					(width 0)
					(fill yes)
				)
			)
		)
	)
	(footprint ""
		(layer "B.Cu")
		(at 102.343966 -58.928 180)
		(property "Reference" "SR864"
			(at 0 0 0)
			(layer "B.SilkS")
			(hide yes)
			(effects
				(font
					(size 1.27 1.27)
				)
				(justify mirror)
			)
		)
		(property "Value" "0R2J-2-GP"
			(at -0.064008 -3.993896 180)
			(unlocked yes)
			(layer "B.Fab")
			(hide yes)
			(effects
				(font
					(size 1.016 1.016)
					(thickness 0.1524)
				)
				(justify mirror)
			)
		)
		(property "Device Type" "R402H16"
			(at -0.064008 -5.517896 180)
			(unlocked yes)
			(layer "B.Fab")
			(hide yes)
			(effects
				(font
					(size 1.016 1.016)
					(thickness 0.1524)
				)
				(justify mirror)
			)
		)
		(duplicate_pad_numbers_are_jumpers no)
		(fp_line
			(start 0.508 -0.9398)
			(end 0.508 0.9398)
			(stroke
				(width 0.1524)
				(type default)
			)
			(layer "B.SilkS")
		)
		(fp_line
			(start -0.508 -0.9398)
			(end 0.508 -0.9398)
			(stroke
				(width 0.1524)
				(type default)
			)
			(layer "B.SilkS")
		)
		(fp_rect
			(start 0.508 0.9398)
			(end -0.508 -0.9398)
			(stroke
				(width 0)
				(type default)
			)
			(fill no)
			(layer "B.CrtYd")
		)
		(fp_rect
			(start 0.508 0.9398)
			(end -0.508 -0.9398)
			(stroke
				(width 0)
				(type default)
			)
			(fill no)
			(layer "B.Fab")
		)
		(pad "1" smd custom
			(at 0 -0.4445)
			(size 0.1397 0.1397)
			(layers "B.Cu" "B.Mask" "B.Paste")
			(net "JTAG_IOC_TCK")
			(options
				(clearance outline)
				(anchor circle)
			)
			(primitives
				(gr_poly
					(pts
						(arc
							(start -0.1778 0.2794)
							(mid -0.249642 0.249642)
							(end -0.2794 0.1778)
						)
						(arc
							(start -0.2794 -0.1778)
							(mid -0.249642 -0.249642)
							(end -0.1778 -0.2794)
						)
						(arc
							(start 0.1778 -0.2794)
							(mid 0.249642 -0.249642)
							(end 0.2794 -0.1778)
						)
						(arc
							(start 0.2794 0.1778)
							(mid 0.249642 0.249642)
							(end 0.1778 0.2794)
						)
					)
					(width 0)
					(fill yes)
				)
			)
		)
		(pad "2" smd custom
			(at 0 0.4445)
			(size 0.1397 0.1397)
			(layers "B.Cu" "B.Mask" "B.Paste")
			(net "JTAG_EXP_IOC_TCK")
			(options
				(clearance outline)
				(anchor circle)
			)
			(primitives
				(gr_poly
					(pts
						(arc
							(start -0.1778 0.2794)
							(mid -0.249642 0.249642)
							(end -0.2794 0.1778)
						)
						(arc
							(start -0.2794 -0.1778)
							(mid -0.249642 -0.249642)
							(end -0.1778 -0.2794)
						)
						(arc
							(start 0.1778 -0.2794)
							(mid 0.249642 -0.249642)
							(end 0.2794 -0.1778)
						)
						(arc
							(start 0.2794 0.1778)
							(mid 0.249642 0.249642)
							(end 0.1778 0.2794)
						)
					)
					(width 0)
					(fill yes)
				)
			)
		)
	)
	(footprint ""
		(layer "B.Cu")
		(at 103.886 -239.395)
		(property "Reference" "SR945"
			(at 0 0 0)
			(layer "B.SilkS")
			(hide yes)
			(effects
				(font
					(size 1.27 1.27)
				)
				(justify mirror)
			)
		)
		(property "Value" "4K7R2F-GP"
			(at -0.064008 -3.993896 0)
			(unlocked yes)
			(layer "B.Fab")
			(hide yes)
			(effects
				(font
					(size 1.016 1.016)
					(thickness 0.1524)
				)
				(justify mirror)
			)
		)
		(property "Device Type" "R402H16"
			(at -0.064008 -5.517896 0)
			(unlocked yes)
			(layer "B.Fab")
			(hide yes)
			(effects
				(font
					(size 1.016 1.016)
					(thickness 0.1524)
				)
				(justify mirror)
			)
		)
		(duplicate_pad_numbers_are_jumpers no)
		(fp_line
			(start -0.508 -0.9398)
			(end 0.508 -0.9398)
			(stroke
				(width 0.1524)
				(type default)
			)
			(layer "B.SilkS")
		)
		(fp_line
			(start 0.508 -0.9398)
			(end 0.508 0.9398)
			(stroke
				(width 0.1524)
				(type default)
			)
			(layer "B.SilkS")
		)
		(fp_rect
			(start 0.508 0.9398)
			(end -0.508 -0.9398)
			(stroke
				(width 0)
				(type default)
			)
			(fill no)
			(layer "B.CrtYd")
		)
		(fp_rect
			(start 0.508 0.9398)
			(end -0.508 -0.9398)
			(stroke
				(width 0)
				(type default)
			)
			(fill no)
			(layer "B.Fab")
		)
		(pad "1" smd custom
			(at 0 -0.4445 180)
			(size 0.1397 0.1397)
			(layers "B.Cu" "B.Mask" "B.Paste")
			(net "SAS_FAULT_LED4")
			(options
				(clearance outline)
				(anchor circle)
			)
			(primitives
				(gr_poly
					(pts
						(arc
							(start -0.1778 0.2794)
							(mid -0.249642 0.249642)
							(end -0.2794 0.1778)
						)
						(arc
							(start -0.2794 -0.1778)
							(mid -0.249642 -0.249642)
							(end -0.1778 -0.2794)
						)
						(arc
							(start 0.1778 -0.2794)
							(mid 0.249642 -0.249642)
							(end 0.2794 -0.1778)
						)
						(arc
							(start 0.2794 0.1778)
							(mid 0.249642 0.249642)
							(end 0.1778 0.2794)
						)
					)
					(width 0)
					(fill yes)
				)
			)
		)
		(pad "2" smd custom
			(at 0 0.4445 180)
			(size 0.1397 0.1397)
			(layers "B.Cu" "B.Mask" "B.Paste")
			(net "P3V3_STBY")
			(options
				(clearance outline)
				(anchor circle)
			)
			(primitives
				(gr_poly
					(pts
						(arc
							(start -0.1778 0.2794)
							(mid -0.249642 0.249642)
							(end -0.2794 0.1778)
						)
						(arc
							(start -0.2794 -0.1778)
							(mid -0.249642 -0.249642)
							(end -0.1778 -0.2794)
						)
						(arc
							(start 0.1778 -0.2794)
							(mid 0.249642 -0.249642)
							(end 0.2794 -0.1778)
						)
						(arc
							(start 0.2794 0.1778)
							(mid 0.249642 0.249642)
							(end 0.1778 0.2794)
						)
					)
					(width 0)
					(fill yes)
				)
			)
		)
	)
	(footprint ""
		(layer "B.Cu")
		(at 114.551206 -39.1033)
		(property "Reference" "STP19"
			(at 0 0 0)
			(layer "B.SilkS")
			(hide yes)
			(effects
				(font
					(size 1.27 1.27)
				)
				(justify mirror)
			)
		)
		(property "Value" "TPAD28"
			(at -0.0127 -1.8034 0)
			(unlocked yes)
			(layer "B.Fab")
			(hide yes)
			(effects
				(font
					(size 1.016 1.016)
					(thickness 0.1524)
				)
				(justify mirror)
			)
		)
		(property "Device Type" "TPAD28"
			(at -0.0127 -3.3274 0)
			(unlocked yes)
			(layer "B.Fab")
			(hide yes)
			(effects
				(font
					(size 1.016 1.016)
					(thickness 0.1524)
				)
				(justify mirror)
			)
		)
		(duplicate_pad_numbers_are_jumpers no)
		(fp_poly
			(pts
				(arc
					(start 0.3556 0)
					(mid -0.3556 0)
					(end 0.3556 0)
				)
			)
			(stroke
				(width 0)
				(type default)
			)
			(fill no)
			(layer "B.CrtYd")
		)
		(fp_poly
			(pts
				(arc
					(start 0.6096 0)
					(mid -0.6096 0)
					(end 0.6096 0)
				)
			)
			(stroke
				(width 0)
				(type default)
			)
			(fill no)
			(layer "B.Fab")
		)
		(pad "1" smd circle
			(at 0 0 180)
			(size 0.7112 0.7112)
			(layers "B.Cu" "B.Mask" "B.Paste")
			(net "IOC_GPIO_34")
		)
	)
	(footprint ""
		(layer "B.Cu")
		(at 42.11193 -77.650086)
		(property "Reference" "SC1274"
			(at 0 0 0)
			(layer "B.SilkS")
			(hide yes)
			(effects
				(font
					(size 1.27 1.27)
				)
				(justify mirror)
			)
		)
		(property "Value" "SCD01U50V2KX-1GP"
			(at -1.1811 -2.7051 0)
			(unlocked yes)
			(layer "B.Fab")
			(hide yes)
			(effects
				(font
					(size 1.016 1.016)
					(thickness 0.1524)
				)
				(justify mirror)
			)
		)
		(property "Device Type" "C402H22"
			(at -1.1811 -4.2291 0)
			(unlocked yes)
			(layer "B.Fab")
			(hide yes)
			(effects
				(font
					(size 1.016 1.016)
					(thickness 0.1524)
				)
				(justify mirror)
			)
		)
		(duplicate_pad_numbers_are_jumpers no)
		(fp_rect
			(start 0.4318 0.9525)
			(end -0.4318 -0.9525)
			(stroke
				(width 0)
				(type default)
			)
			(fill no)
			(layer "B.CrtYd")
		)
		(fp_rect
			(start 0.4318 0.9525)
			(end -0.4318 -0.9525)
			(stroke
				(width 0)
				(type default)
			)
			(fill no)
			(layer "B.Fab")
		)
		(pad "1" smd custom
			(at 0 -0.4445 180)
			(size 0.1524 0.1524)
			(layers "B.Cu" "B.Mask" "B.Paste")
			(net "SAS_EXP2CONN_RX_P_20")
			(options
				(clearance outline)
				(anchor circle)
			)
			(primitives
				(gr_poly
					(pts
						(arc
							(start 0.3048 0.2032)
							(mid 0.275042 0.275042)
							(end 0.2032 0.3048)
						)
						(arc
							(start -0.2032 0.3048)
							(mid -0.275042 0.275042)
							(end -0.3048 0.2032)
						)
						(arc
							(start -0.3048 -0.2032)
							(mid -0.275042 -0.275042)
							(end -0.2032 -0.3048)
						)
						(arc
							(start 0.2032 -0.3048)
							(mid 0.275042 -0.275042)
							(end 0.3048 -0.2032)
						)
					)
					(width 0)
					(fill yes)
				)
			)
		)
		(pad "2" smd custom
			(at 0 0.4445 180)
			(size 0.1524 0.1524)
			(layers "B.Cu" "B.Mask" "B.Paste")
			(net "MINI_RX_P_20")
			(options
				(clearance outline)
				(anchor circle)
			)
			(primitives
				(gr_poly
					(pts
						(arc
							(start 0.3048 0.2032)
							(mid 0.275042 0.275042)
							(end 0.2032 0.3048)
						)
						(arc
							(start -0.2032 0.3048)
							(mid -0.275042 0.275042)
							(end -0.3048 0.2032)
						)
						(arc
							(start -0.3048 -0.2032)
							(mid -0.275042 -0.275042)
							(end -0.2032 -0.3048)
						)
						(arc
							(start 0.2032 -0.3048)
							(mid 0.275042 -0.275042)
							(end 0.3048 -0.2032)
						)
					)
					(width 0)
					(fill yes)
				)
			)
		)
	)
	(footprint ""
		(layer "B.Cu")
		(at 79.883 -18.796 180)
		(property "Reference" "PC213"
			(at 0 0 0)
			(layer "B.SilkS")
			(hide yes)
			(effects
				(font
					(size 1.27 1.27)
				)
				(justify mirror)
			)
		)
		(property "Value" "SC1U25V3KX-GP"
			(at 0 -2.8194 180)
			(unlocked yes)
			(layer "B.Fab")
			(hide yes)
			(effects
				(font
					(size 1.016 1.016)
					(thickness 0.1524)
				)
				(justify mirror)
			)
		)
		(property "Device Type" "C603H36"
			(at 0 -4.3434 180)
			(unlocked yes)
			(layer "B.Fab")
			(hide yes)
			(effects
				(font
					(size 1.016 1.016)
					(thickness 0.1524)
				)
				(justify mirror)
			)
		)
		(duplicate_pad_numbers_are_jumpers no)
		(fp_line
			(start -0.508 0)
			(end 0.508 0)
			(stroke
				(width 0.2032)
				(type default)
			)
			(layer "B.SilkS")
		)
		(fp_rect
			(start 0.5842 1.3335)
			(end -0.5842 -1.3335)
			(stroke
				(width 0)
				(type default)
			)
			(fill no)
			(layer "B.CrtYd")
		)
		(fp_rect
			(start 0.5842 1.3335)
			(end -0.5842 -1.3335)
			(stroke
				(width 0)
				(type default)
			)
			(fill no)
			(layer "B.Fab")
		)
		(pad "1" smd custom
			(at 0 -0.762)
			(size 0.2159 0.2159)
			(layers "B.Cu" "B.Mask" "B.Paste")
			(net "VT235_AVDD")
			(options
				(clearance outline)
				(anchor circle)
			)
			(primitives
				(gr_poly
					(pts
						(arc
							(start -0.3302 0.4318)
							(mid -0.402042 0.402042)
							(end -0.4318 0.3302)
						)
						(arc
							(start -0.4318 -0.3302)
							(mid -0.402042 -0.402042)
							(end -0.3302 -0.4318)
						)
						(arc
							(start 0.3302 -0.4318)
							(mid 0.402042 -0.402042)
							(end 0.4318 -0.3302)
						)
						(arc
							(start 0.4318 0.3302)
							(mid 0.402042 0.402042)
							(end 0.3302 0.4318)
						)
					)
					(width 0)
					(fill yes)
				)
			)
		)
		(pad "2" smd custom
			(at 0 0.762)
			(size 0.2159 0.2159)
			(layers "B.Cu" "B.Mask" "B.Paste")
			(net "AGND_P0V9_C")
			(options
				(clearance outline)
				(anchor circle)
			)
			(primitives
				(gr_poly
					(pts
						(arc
							(start -0.3302 0.4318)
							(mid -0.402042 0.402042)
							(end -0.4318 0.3302)
						)
						(arc
							(start -0.4318 -0.3302)
							(mid -0.402042 -0.402042)
							(end -0.3302 -0.4318)
						)
						(arc
							(start 0.3302 -0.4318)
							(mid 0.402042 -0.402042)
							(end 0.4318 -0.3302)
						)
						(arc
							(start 0.4318 0.3302)
							(mid 0.402042 0.402042)
							(end 0.3302 0.4318)
						)
					)
					(width 0)
					(fill yes)
				)
			)
		)
	)
	(footprint ""
		(layer "B.Cu")
		(at 115.902486 -40.06596)
		(property "Reference" "STP17"
			(at 0 0 0)
			(layer "B.SilkS")
			(hide yes)
			(effects
				(font
					(size 1.27 1.27)
				)
				(justify mirror)
			)
		)
		(property "Value" "TPAD28"
			(at -0.0127 -1.8034 0)
			(unlocked yes)
			(layer "B.Fab")
			(hide yes)
			(effects
				(font
					(size 1.016 1.016)
					(thickness 0.1524)
				)
				(justify mirror)
			)
		)
		(property "Device Type" "TPAD28"
			(at -0.0127 -3.3274 0)
			(unlocked yes)
			(layer "B.Fab")
			(hide yes)
			(effects
				(font
					(size 1.016 1.016)
					(thickness 0.1524)
				)
				(justify mirror)
			)
		)
		(duplicate_pad_numbers_are_jumpers no)
		(fp_poly
			(pts
				(arc
					(start 0.3556 0)
					(mid -0.3556 0)
					(end 0.3556 0)
				)
			)
			(stroke
				(width 0)
				(type default)
			)
			(fill no)
			(layer "B.CrtYd")
		)
		(fp_poly
			(pts
				(arc
					(start 0.6096 0)
					(mid -0.6096 0)
					(end 0.6096 0)
				)
			)
			(stroke
				(width 0)
				(type default)
			)
			(fill no)
			(layer "B.Fab")
		)
		(pad "1" smd circle
			(at 0 0 180)
			(size 0.7112 0.7112)
			(layers "B.Cu" "B.Mask" "B.Paste")
			(net "IOC_GPIO_33")
		)
	)
)
